(kicad_pcb
	(version 20260206)
	(generator "pcbnew")
	(generator_version "10.0")
	(general
		(thickness 1.6)
		(legacy_teardrops no)
	)
	(paper "A4")
	(title_block
		(title "03242023_DA0F0TMBIJ0_F0T_Motherboard_J_brd_V01_OCP.brd")
		(comment 1 "Grand Teton / footprints 4990-4997 of 6105")
	)
	(layers
		(0 "F.Cu" signal "TOP")
		(4 "In1.Cu" signal "GND")
		(6 "In2.Cu" signal "IN1")
		(8 "In3.Cu" signal "GND1")
		(10 "In4.Cu" signal "IN2")
		(12 "In5.Cu" signal "GND2")
		(14 "In6.Cu" signal "IN3")
		(16 "In7.Cu" signal "GND3")
		(18 "In8.Cu" signal "VCC")
		(20 "In9.Cu" signal "VCC1")
		(22 "In10.Cu" signal "GND4")
		(24 "In11.Cu" signal "IN4")
		(26 "In12.Cu" signal "GND5")
		(28 "In13.Cu" signal "IN5")
		(30 "In14.Cu" signal "GND6")
		(32 "In15.Cu" signal "IN6")
		(34 "In16.Cu" signal "GND7")
		(2 "B.Cu" signal "BOTTOM")
		(9 "F.Adhes" user "F.Adhesive")
		(11 "B.Adhes" user "B.Adhesive")
		(13 "F.Paste" user "Package Geometry/Pastemask Top")
		(15 "B.Paste" user "Package Geometry/Pastemask Bottom")
		(5 "F.SilkS" user "Ref Des/Silkscreen Top")
		(7 "B.SilkS" user "Ref Des/Silkscreen Bottom")
		(1 "F.Mask" user "Board Geometry/Soldermask Top")
		(3 "B.Mask" user "Board Geometry/Soldermask Bottom")
		(17 "Dwgs.User" user "User.Drawings")
		(19 "Cmts.User" user "User.Comments")
		(21 "Eco1.User" user "User.Eco1")
		(23 "Eco2.User" user "User.Eco2")
		(25 "Edge.Cuts" user "Board Geometry/Outline")
		(27 "Margin" user)
		(31 "F.CrtYd" user "Package Geometry/Place Bound Top")
		(29 "B.CrtYd" user "Package Geometry/Place Bound Bottom")
		(35 "F.Fab" user "Ref Des/Assembly Top")
		(33 "B.Fab" user "Ref Des/Assembly Bottom")
	)
	(footprint ""
		(layer "B.Cu")
		(at 378.711968 -190.795656 -90)
		(property "Reference" "R686"
			(at 0 0 90)
			(layer "B.SilkS")
			(hide yes)
			(effects
				(font
					(size 1.27 1.27)
				)
				(justify mirror)
			)
		)
		(property "Value" ""
			(at 0 0 90)
			(layer "B.Fab")
			(effects
				(font
					(size 1.27 1.27)
				)
				(justify mirror)
			)
		)
		(duplicate_pad_numbers_are_jumpers no)
		(fp_line
			(start -0.7874 0.4064)
			(end 0.7874 0.4064)
			(stroke
				(width 0.1524)
				(type default)
			)
			(layer "B.SilkS")
		)
		(fp_line
			(start 0.7874 0.4064)
			(end 0.7874 -0.4064)
			(stroke
				(width 0.1524)
				(type default)
			)
			(layer "B.SilkS")
		)
		(fp_line
			(start -0.7874 -0.4064)
			(end -0.7874 0.4064)
			(stroke
				(width 0.1524)
				(type default)
			)
			(layer "B.SilkS")
		)
		(fp_line
			(start 0.7874 -0.4064)
			(end -0.7874 -0.4064)
			(stroke
				(width 0.1524)
				(type default)
			)
			(layer "B.SilkS")
		)
		(fp_line
			(start -0.67945 0.3048)
			(end -0.120396 0.3048)
			(stroke
				(width 0.1)
				(type default)
			)
			(layer "B.Fab")
		)
		(fp_line
			(start -0.120396 0.3048)
			(end -0.120396 0.2794)
			(stroke
				(width 0.1)
				(type default)
			)
			(layer "B.Fab")
		)
		(fp_line
			(start 0.12065 0.3048)
			(end 0.67945 0.3048)
			(stroke
				(width 0.1)
				(type default)
			)
			(layer "B.Fab")
		)
		(fp_line
			(start 0.67945 0.3048)
			(end 0.67945 -0.305054)
			(stroke
				(width 0.1)
				(type default)
			)
			(layer "B.Fab")
		)
		(fp_line
			(start -0.120396 0.2794)
			(end 0.12065 0.2794)
			(stroke
				(width 0.1)
				(type default)
			)
			(layer "B.Fab")
		)
		(fp_line
			(start 0.12065 0.2794)
			(end 0.12065 0.3048)
			(stroke
				(width 0.1)
				(type default)
			)
			(layer "B.Fab")
		)
		(fp_line
			(start -0.12065 -0.2794)
			(end -0.12065 -0.3048)
			(stroke
				(width 0.1)
				(type default)
			)
			(layer "B.Fab")
		)
		(fp_line
			(start 0.12065 -0.2794)
			(end -0.12065 -0.2794)
			(stroke
				(width 0.1)
				(type default)
			)
			(layer "B.Fab")
		)
		(fp_line
			(start -0.67945 -0.3048)
			(end -0.67945 0.3048)
			(stroke
				(width 0.1)
				(type default)
			)
			(layer "B.Fab")
		)
		(fp_line
			(start -0.12065 -0.3048)
			(end -0.67945 -0.3048)
			(stroke
				(width 0.1)
				(type default)
			)
			(layer "B.Fab")
		)
		(fp_line
			(start 0.12065 -0.305054)
			(end 0.12065 -0.2794)
			(stroke
				(width 0.1)
				(type default)
			)
			(layer "B.Fab")
		)
		(fp_line
			(start 0.67945 -0.305054)
			(end 0.12065 -0.305054)
			(stroke
				(width 0.1)
				(type default)
			)
			(layer "B.Fab")
		)
		(pad "1" smd circle
			(at 0.40005 0 90)
			(size 0 0)
			(layers "B.Cu" "B.Mask" "B.Paste")
			(net "PVNN_TERM_CPU0")
		)
		(pad "2" smd circle
			(at -0.40005 0 90)
			(size 0 0)
			(layers "B.Cu" "B.Mask" "B.Paste")
			(net "I3C_SPD_DDREFGH_CPU0_SDA")
		)
	)
	(footprint ""
		(layer "B.Cu")
		(at 364.342934 -244.820186 -90)
		(property "Reference" "C379"
			(at 0 0 90)
			(layer "B.SilkS")
			(hide yes)
			(effects
				(font
					(size 1.27 1.27)
				)
				(justify mirror)
			)
		)
		(property "Value" ""
			(at 0 0 90)
			(layer "B.Fab")
			(effects
				(font
					(size 1.27 1.27)
				)
				(justify mirror)
			)
		)
		(duplicate_pad_numbers_are_jumpers no)
		(fp_line
			(start -1.524 0.762)
			(end 1.524 0.762)
			(stroke
				(width 0.1524)
				(type default)
			)
			(layer "B.SilkS")
		)
		(fp_line
			(start 1.524 0.762)
			(end 1.524 -0.762)
			(stroke
				(width 0.1524)
				(type default)
			)
			(layer "B.SilkS")
		)
		(fp_line
			(start -1.524 -0.762)
			(end -1.524 0.762)
			(stroke
				(width 0.1524)
				(type default)
			)
			(layer "B.SilkS")
		)
		(fp_line
			(start 1.524 -0.762)
			(end -1.524 -0.762)
			(stroke
				(width 0.1524)
				(type default)
			)
			(layer "B.SilkS")
		)
		(fp_line
			(start -1.1049 0.724916)
			(end -1.1049 -0.724916)
			(stroke
				(width 0.1)
				(type default)
			)
			(layer "B.Fab")
		)
		(fp_line
			(start 1.1049 0.724916)
			(end -1.1049 0.724916)
			(stroke
				(width 0.1)
				(type default)
			)
			(layer "B.Fab")
		)
		(fp_line
			(start -1.1049 -0.724916)
			(end 1.1049 -0.724916)
			(stroke
				(width 0.1)
				(type default)
			)
			(layer "B.Fab")
		)
		(fp_line
			(start 1.1049 -0.724916)
			(end 1.1049 0.724916)
			(stroke
				(width 0.1)
				(type default)
			)
			(layer "B.Fab")
		)
		(pad "1" smd rect
			(at 0.889 0 270)
			(size 1.016 1.27)
			(layers "B.Cu" "B.Mask" "B.Paste")
			(net "PVCCIN_CPU0")
		)
		(pad "2" smd rect
			(at -0.889 0 270)
			(size 1.016 1.27)
			(layers "B.Cu" "B.Mask" "B.Paste")
			(net "GND")
		)
	)
	(footprint ""
		(layer "B.Cu")
		(at 436.941214 -321.549776 -90)
		(property "Reference" "C42"
			(at 0 0 90)
			(layer "B.SilkS")
			(hide yes)
			(effects
				(font
					(size 1.27 1.27)
				)
				(justify mirror)
			)
		)
		(property "Value" ""
			(at 0 0 90)
			(layer "B.Fab")
			(effects
				(font
					(size 1.27 1.27)
				)
				(justify mirror)
			)
		)
		(duplicate_pad_numbers_are_jumpers no)
		(fp_line
			(start -1.524 0.762)
			(end 1.524 0.762)
			(stroke
				(width 0.1524)
				(type default)
			)
			(layer "B.SilkS")
		)
		(fp_line
			(start 1.524 0.762)
			(end 1.524 -0.762)
			(stroke
				(width 0.1524)
				(type default)
			)
			(layer "B.SilkS")
		)
		(fp_line
			(start -1.524 -0.762)
			(end -1.524 0.762)
			(stroke
				(width 0.1524)
				(type default)
			)
			(layer "B.SilkS")
		)
		(fp_line
			(start 1.524 -0.762)
			(end -1.524 -0.762)
			(stroke
				(width 0.1524)
				(type default)
			)
			(layer "B.SilkS")
		)
		(fp_line
			(start -1.1049 0.724916)
			(end -1.1049 -0.724916)
			(stroke
				(width 0.1)
				(type default)
			)
			(layer "B.Fab")
		)
		(fp_line
			(start 1.1049 0.724916)
			(end -1.1049 0.724916)
			(stroke
				(width 0.1)
				(type default)
			)
			(layer "B.Fab")
		)
		(fp_line
			(start -1.1049 -0.724916)
			(end 1.1049 -0.724916)
			(stroke
				(width 0.1)
				(type default)
			)
			(layer "B.Fab")
		)
		(fp_line
			(start 1.1049 -0.724916)
			(end 1.1049 0.724916)
			(stroke
				(width 0.1)
				(type default)
			)
			(layer "B.Fab")
		)
		(pad "1" smd rect
			(at 0.889 0 270)
			(size 1.016 1.27)
			(layers "B.Cu" "B.Mask" "B.Paste")
			(net "P12V_S3_AUX_CPU0_NVDIMM")
		)
		(pad "2" smd rect
			(at -0.889 0 270)
			(size 1.016 1.27)
			(layers "B.Cu" "B.Mask" "B.Paste")
			(net "GND")
		)
	)
	(footprint ""
		(layer "B.Cu")
		(at 353.610418 -296.054526)
		(property "Reference" "C388"
			(at 0 0 0)
			(layer "B.SilkS")
			(hide yes)
			(effects
				(font
					(size 1.27 1.27)
				)
				(justify mirror)
			)
		)
		(property "Value" ""
			(at 0 0 0)
			(layer "B.Fab")
			(effects
				(font
					(size 1.27 1.27)
				)
				(justify mirror)
			)
		)
		(duplicate_pad_numbers_are_jumpers no)
		(fp_line
			(start -1.524 -0.762)
			(end -1.524 0.762)
			(stroke
				(width 0.1524)
				(type default)
			)
			(layer "B.SilkS")
		)
		(fp_line
			(start -1.524 0.762)
			(end 1.524 0.762)
			(stroke
				(width 0.1524)
				(type default)
			)
			(layer "B.SilkS")
		)
		(fp_line
			(start 1.524 -0.762)
			(end -1.524 -0.762)
			(stroke
				(width 0.1524)
				(type default)
			)
			(layer "B.SilkS")
		)
		(fp_line
			(start 1.524 0.762)
			(end 1.524 -0.762)
			(stroke
				(width 0.1524)
				(type default)
			)
			(layer "B.SilkS")
		)
		(fp_line
			(start -1.1049 -0.724916)
			(end 1.1049 -0.724916)
			(stroke
				(width 0.1)
				(type default)
			)
			(layer "B.Fab")
		)
		(fp_line
			(start -1.1049 0.724916)
			(end -1.1049 -0.724916)
			(stroke
				(width 0.1)
				(type default)
			)
			(layer "B.Fab")
		)
		(fp_line
			(start 1.1049 -0.724916)
			(end 1.1049 0.724916)
			(stroke
				(width 0.1)
				(type default)
			)
			(layer "B.Fab")
		)
		(fp_line
			(start 1.1049 0.724916)
			(end -1.1049 0.724916)
			(stroke
				(width 0.1)
				(type default)
			)
			(layer "B.Fab")
		)
		(pad "1" smd rect
			(at 0.889 0)
			(size 1.016 1.27)
			(layers "B.Cu" "B.Mask" "B.Paste")
			(net "PVCCIN_CPU0")
		)
		(pad "2" smd rect
			(at -0.889 0)
			(size 1.016 1.27)
			(layers "B.Cu" "B.Mask" "B.Paste")
			(net "GND")
		)
	)
	(footprint ""
		(layer "B.Cu")
		(at 423.799762 -134.19709 180)
		(property "Reference" "PR123"
			(at 0 0 0)
			(layer "B.SilkS")
			(hide yes)
			(effects
				(font
					(size 1.27 1.27)
				)
				(justify mirror)
			)
		)
		(property "Value" ""
			(at 0 0 0)
			(layer "B.Fab")
			(effects
				(font
					(size 1.27 1.27)
				)
				(justify mirror)
			)
		)
		(duplicate_pad_numbers_are_jumpers no)
		(fp_line
			(start 0.7874 0.4064)
			(end 0.7874 -0.4064)
			(stroke
				(width 0.1524)
				(type default)
			)
			(layer "B.SilkS")
		)
		(fp_line
			(start 0.7874 -0.4064)
			(end -0.7874 -0.4064)
			(stroke
				(width 0.1524)
				(type default)
			)
			(layer "B.SilkS")
		)
		(fp_line
			(start -0.7874 0.4064)
			(end 0.7874 0.4064)
			(stroke
				(width 0.1524)
				(type default)
			)
			(layer "B.SilkS")
		)
		(fp_line
			(start -0.7874 -0.4064)
			(end -0.7874 0.4064)
			(stroke
				(width 0.1524)
				(type default)
			)
			(layer "B.SilkS")
		)
		(fp_line
			(start 0.67945 0.3048)
			(end 0.67945 -0.305054)
			(stroke
				(width 0.1)
				(type default)
			)
			(layer "B.Fab")
		)
		(fp_line
			(start 0.67945 -0.305054)
			(end 0.12065 -0.305054)
			(stroke
				(width 0.1)
				(type default)
			)
			(layer "B.Fab")
		)
		(fp_line
			(start 0.12065 0.3048)
			(end 0.67945 0.3048)
			(stroke
				(width 0.1)
				(type default)
			)
			(layer "B.Fab")
		)
		(fp_line
			(start 0.12065 0.2794)
			(end 0.12065 0.3048)
			(stroke
				(width 0.1)
				(type default)
			)
			(layer "B.Fab")
		)
		(fp_line
			(start 0.12065 -0.2794)
			(end -0.12065 -0.2794)
			(stroke
				(width 0.1)
				(type default)
			)
			(layer "B.Fab")
		)
		(fp_line
			(start 0.12065 -0.305054)
			(end 0.12065 -0.2794)
			(stroke
				(width 0.1)
				(type default)
			)
			(layer "B.Fab")
		)
		(fp_line
			(start -0.120396 0.3048)
			(end -0.120396 0.2794)
			(stroke
				(width 0.1)
				(type default)
			)
			(layer "B.Fab")
		)
		(fp_line
			(start -0.120396 0.2794)
			(end 0.12065 0.2794)
			(stroke
				(width 0.1)
				(type default)
			)
			(layer "B.Fab")
		)
		(fp_line
			(start -0.12065 -0.2794)
			(end -0.12065 -0.3048)
			(stroke
				(width 0.1)
				(type default)
			)
			(layer "B.Fab")
		)
		(fp_line
			(start -0.12065 -0.3048)
			(end -0.67945 -0.3048)
			(stroke
				(width 0.1)
				(type default)
			)
			(layer "B.Fab")
		)
		(fp_line
			(start -0.67945 0.3048)
			(end -0.120396 0.3048)
			(stroke
				(width 0.1)
				(type default)
			)
			(layer "B.Fab")
		)
		(fp_line
			(start -0.67945 -0.3048)
			(end -0.67945 0.3048)
			(stroke
				(width 0.1)
				(type default)
			)
			(layer "B.Fab")
		)
		(pad "1" smd circle
			(at 0.40005 0)
			(size 0 0)
			(layers "B.Cu" "B.Mask" "B.Paste")
			(net "PVCCINFAON_CPU0_VIN_CSNIN")
		)
		(pad "2" smd circle
			(at -0.40005 0)
			(size 0 0)
			(layers "B.Cu" "B.Mask" "B.Paste")
			(net "GND")
		)
	)
	(footprint ""
		(layer "B.Cu")
		(at 477.827594 -343.149682)
		(property "Reference" "DB11"
			(at 2.502662 -5.374386 270)
			(unlocked yes)
			(layer "B.SilkS")
			(effects
				(font
					(size 0.7874 0.5842)
					(thickness 0.1524)
				)
				(justify left mirror)
			)
		)
		(property "Value" ""
			(at 0 0 0)
			(layer "B.Fab")
			(effects
				(font
					(size 1.27 1.27)
				)
				(justify mirror)
			)
		)
		(duplicate_pad_numbers_are_jumpers no)
		(fp_line
			(start -3.330702 -4.771136)
			(end 0 4.011168)
			(stroke
				(width 0.1524)
				(type default)
			)
			(layer "B.SilkS")
		)
		(fp_line
			(start 0 4.011168)
			(end 3.330702 -4.771136)
			(stroke
				(width 0.1524)
				(type default)
			)
			(layer "B.SilkS")
		)
		(fp_line
			(start 3.330702 -4.771136)
			(end -3.330702 -4.771136)
			(stroke
				(width 0.1524)
				(type default)
			)
			(layer "B.SilkS")
		)
		(fp_line
			(start -3.330702 -4.771136)
			(end 0 4.011168)
			(stroke
				(width 0.1)
				(type default)
			)
			(layer "B.Fab")
		)
		(fp_line
			(start 0 4.011168)
			(end 3.330702 -4.771136)
			(stroke
				(width 0.1)
				(type default)
			)
			(layer "B.Fab")
		)
		(fp_line
			(start 3.330702 -4.771136)
			(end -3.330702 -4.771136)
			(stroke
				(width 0.1)
				(type default)
			)
			(layer "B.Fab")
		)
		(pad "1" thru_hole circle
			(at 0 0 180)
			(size 2.159 2.159)
			(drill 1.7018)
			(layers "*.Cu" "*.Mask")
			(remove_unused_layers no)
			(net "T1_GND")
			(clearance 0.0254)
			(thermal_gap 0.0254)
		)
		(pad "2" thru_hole circle
			(at 1.27 -3.348736 180)
			(size 2.159 2.159)
			(drill 1.7018)
			(layers "*.Cu" "*.Mask")
			(remove_unused_layers no)
			(net "TDR_SE_50_OHM_IN4")
			(clearance 0.0254)
			(thermal_gap 0.0254)
		)
		(pad "3" thru_hole circle
			(at -1.27 -3.348736 180)
			(size 2.159 2.159)
			(drill 1.7018)
			(layers "*.Cu" "*.Mask")
			(remove_unused_layers no)
			(net "TDR_SE_50_OHM_IN4")
			(clearance 0.0254)
			(thermal_gap 0.0254)
		)
	)
	(footprint ""
		(layer "B.Cu")
		(at 80.763618 -190.83401 90)
		(property "Reference" "R51"
			(at 0 0 90)
			(layer "B.SilkS")
			(hide yes)
			(effects
				(font
					(size 1.27 1.27)
				)
				(justify mirror)
			)
		)
		(property "Value" ""
			(at 0 0 90)
			(layer "B.Fab")
			(effects
				(font
					(size 1.27 1.27)
				)
				(justify mirror)
			)
		)
		(duplicate_pad_numbers_are_jumpers no)
		(fp_line
			(start 0.7874 -0.4064)
			(end -0.7874 -0.4064)
			(stroke
				(width 0.1524)
				(type default)
			)
			(layer "B.SilkS")
		)
		(fp_line
			(start -0.7874 -0.4064)
			(end -0.7874 0.4064)
			(stroke
				(width 0.1524)
				(type default)
			)
			(layer "B.SilkS")
		)
		(fp_line
			(start 0.7874 0.4064)
			(end 0.7874 -0.4064)
			(stroke
				(width 0.1524)
				(type default)
			)
			(layer "B.SilkS")
		)
		(fp_line
			(start -0.7874 0.4064)
			(end 0.7874 0.4064)
			(stroke
				(width 0.1524)
				(type default)
			)
			(layer "B.SilkS")
		)
		(fp_line
			(start 0.67945 -0.305054)
			(end 0.12065 -0.305054)
			(stroke
				(width 0.1)
				(type default)
			)
			(layer "B.Fab")
		)
		(fp_line
			(start 0.12065 -0.305054)
			(end 0.12065 -0.2794)
			(stroke
				(width 0.1)
				(type default)
			)
			(layer "B.Fab")
		)
		(fp_line
			(start -0.12065 -0.3048)
			(end -0.67945 -0.3048)
			(stroke
				(width 0.1)
				(type default)
			)
			(layer "B.Fab")
		)
		(fp_line
			(start -0.67945 -0.3048)
			(end -0.67945 0.3048)
			(stroke
				(width 0.1)
				(type default)
			)
			(layer "B.Fab")
		)
		(fp_line
			(start 0.12065 -0.2794)
			(end -0.12065 -0.2794)
			(stroke
				(width 0.1)
				(type default)
			)
			(layer "B.Fab")
		)
		(fp_line
			(start -0.12065 -0.2794)
			(end -0.12065 -0.3048)
			(stroke
				(width 0.1)
				(type default)
			)
			(layer "B.Fab")
		)
		(fp_line
			(start 0.12065 0.2794)
			(end 0.12065 0.3048)
			(stroke
				(width 0.1)
				(type default)
			)
			(layer "B.Fab")
		)
		(fp_line
			(start -0.120396 0.2794)
			(end 0.12065 0.2794)
			(stroke
				(width 0.1)
				(type default)
			)
			(layer "B.Fab")
		)
		(fp_line
			(start 0.67945 0.3048)
			(end 0.67945 -0.305054)
			(stroke
				(width 0.1)
				(type default)
			)
			(layer "B.Fab")
		)
		(fp_line
			(start 0.12065 0.3048)
			(end 0.67945 0.3048)
			(stroke
				(width 0.1)
				(type default)
			)
			(layer "B.Fab")
		)
		(fp_line
			(start -0.120396 0.3048)
			(end -0.120396 0.2794)
			(stroke
				(width 0.1)
				(type default)
			)
			(layer "B.Fab")
		)
		(fp_line
			(start -0.67945 0.3048)
			(end -0.120396 0.3048)
			(stroke
				(width 0.1)
				(type default)
			)
			(layer "B.Fab")
		)
		(pad "1" smd circle
			(at 0.40005 0 270)
			(size 0 0)
			(layers "B.Cu" "B.Mask" "B.Paste")
			(net "DBP_CPU1_MBP0_GTL_R_N")
		)
		(pad "2" smd circle
			(at -0.40005 0 270)
			(size 0 0)
			(layers "B.Cu" "B.Mask" "B.Paste")
			(net "DBP_CPU_MBP0_GTL_N")
		)
	)
	(footprint ""
		(layer "B.Cu")
		(at 353.619308 -252.176026 -90)
		(property "Reference" "C368"
			(at 0 0 90)
			(layer "B.SilkS")
			(hide yes)
			(effects
				(font
					(size 1.27 1.27)
				)
				(justify mirror)
			)
		)
		(property "Value" ""
			(at 0 0 90)
			(layer "B.Fab")
			(effects
				(font
					(size 1.27 1.27)
				)
				(justify mirror)
			)
		)
		(duplicate_pad_numbers_are_jumpers no)
		(fp_line
			(start -1.524 0.762)
			(end 1.524 0.762)
			(stroke
				(width 0.1524)
				(type default)
			)
			(layer "B.SilkS")
		)
		(fp_line
			(start 1.524 0.762)
			(end 1.524 -0.762)
			(stroke
				(width 0.1524)
				(type default)
			)
			(layer "B.SilkS")
		)
		(fp_line
			(start -1.524 -0.762)
			(end -1.524 0.762)
			(stroke
				(width 0.1524)
				(type default)
			)
			(layer "B.SilkS")
		)
		(fp_line
			(start 1.524 -0.762)
			(end -1.524 -0.762)
			(stroke
				(width 0.1524)
				(type default)
			)
			(layer "B.SilkS")
		)
		(fp_line
			(start -1.1049 0.724916)
			(end -1.1049 -0.724916)
			(stroke
				(width 0.1)
				(type default)
			)
			(layer "B.Fab")
		)
		(fp_line
			(start 1.1049 0.724916)
			(end -1.1049 0.724916)
			(stroke
				(width 0.1)
				(type default)
			)
			(layer "B.Fab")
		)
		(fp_line
			(start -1.1049 -0.724916)
			(end 1.1049 -0.724916)
			(stroke
				(width 0.1)
				(type default)
			)
			(layer "B.Fab")
		)
		(fp_line
			(start 1.1049 -0.724916)
			(end 1.1049 0.724916)
			(stroke
				(width 0.1)
				(type default)
			)
			(layer "B.Fab")
		)
		(pad "1" smd rect
			(at 0.889 0 270)
			(size 1.016 1.27)
			(layers "B.Cu" "B.Mask" "B.Paste")
			(net "PVCCIN_CPU0")
		)
		(pad "2" smd rect
			(at -0.889 0 270)
			(size 1.016 1.27)
			(layers "B.Cu" "B.Mask" "B.Paste")
			(net "GND")
		)
	)
)
